FILE_TYPE=LIBRARY_PARTS;
primitive 'M24128BWMN6TP';
  pin
    'VCC':
      PIN_NUMBER='(8)';
      PINUSE='POWER';
      NO_LOAD_CHECK='Both';
      NO_IO_CHECK='Both';
      NO_ASSERT_CHECK='TRUE';
      NO_DIR_CHECK='TRUE';
      ALLOW_CONNECT='TRUE';
    'WC#':
      PIN_NUMBER='(7)';
      INPUT_LOAD='(-0.01,0.01)';
    'SCL':
      PIN_NUMBER='(6)';
      INPUT_LOAD='(-0.01,0.01)';
    'SDA':
      PIN_NUMBER='(5)';
      BIDIRECTIONAL='TRUE';
      INPUT_LOAD='(-0.01,0.01)';
      OUTPUT_LOAD='(1.0,-1.0)';
    'VSS':
      PIN_NUMBER='(4)';
      PINUSE='POWER';
      NO_LOAD_CHECK='Both';
      NO_IO_CHECK='Both';
      NO_ASSERT_CHECK='TRUE';
      NO_DIR_CHECK='TRUE';
      ALLOW_CONNECT='TRUE';
    'E2':
      PIN_NUMBER='(3)';
      INPUT_LOAD='(-0.01,0.01)';
    'E1':
      PIN_NUMBER='(2)';
      INPUT_LOAD='(-0.01,0.01)';
    'E0':
      PIN_NUMBER='(1)';
      INPUT_LOAD='(-0.01,0.01)';
  end_pin;
  body
    PART_NAME='M24128BWMN6TP';
    BODY_NAME='M24128BWMN6TP';
    PHYS_DES_PREFIX='U';
    CLASS='IC';
  end_body;
end_primitive;

END.
